(kicad_pcb
	(version 20260206)
	(generator "pcbnew")
	(generator_version "10.0")
	(general
		(thickness 1.6)
		(legacy_teardrops no)
	)
	(paper "A4")
	(title_block
		(title "9054_F0T_PDB_BD_GPU_F_V04_1213_1550_OCP.brd")
		(comment 1 "Grand Teton / footprints 503-509 of 608")
	)
	(layers
		(0 "F.Cu" signal "TOP")
		(4 "In1.Cu" signal "GND")
		(6 "In2.Cu" signal "IN1")
		(8 "In3.Cu" signal "GND1")
		(10 "In4.Cu" signal "VCC")
		(12 "In5.Cu" signal "VCC1")
		(14 "In6.Cu" signal "GND2")
		(16 "In7.Cu" signal "IN2")
		(18 "In8.Cu" signal "GND3")
		(2 "B.Cu" signal "BOTTOM")
		(9 "F.Adhes" user "F.Adhesive")
		(11 "B.Adhes" user "B.Adhesive")
		(13 "F.Paste" user "Package Geometry/Pastemask Top")
		(15 "B.Paste" user "Package Geometry/Pastemask Bottom")
		(5 "F.SilkS" user "Ref Des/Silkscreen Top")
		(7 "B.SilkS" user "Ref Des/Silkscreen Bottom")
		(1 "F.Mask" user "Board Geometry/Soldermask Top")
		(3 "B.Mask" user "Board Geometry/Soldermask Bottom")
		(17 "Dwgs.User" user "User.Drawings")
		(19 "Cmts.User" user "User.Comments")
		(21 "Eco1.User" user "User.Eco1")
		(23 "Eco2.User" user "User.Eco2")
		(25 "Edge.Cuts" user "Board Geometry/Outline")
		(27 "Margin" user)
		(31 "F.CrtYd" user "Package Geometry/Place Bound Top")
		(29 "B.CrtYd" user "Package Geometry/Place Bound Bottom")
		(35 "F.Fab" user "Ref Des/Assembly Top")
		(33 "B.Fab" user "Ref Des/Assembly Bottom")
	)
	(footprint ""
		(layer "B.Cu")
		(at 413.639 -38.989 180)
		(property "Reference" "R5930"
			(at 0 0 0)
			(layer "B.SilkS")
			(hide yes)
			(effects
				(font
					(size 1.27 1.27)
				)
				(justify mirror)
			)
		)
		(property "Value" ""
			(at 0 0 0)
			(layer "B.Fab")
			(effects
				(font
					(size 1.27 1.27)
				)
				(justify mirror)
			)
		)
		(duplicate_pad_numbers_are_jumpers no)
		(fp_line
			(start 0.7874 0.4064)
			(end 0.7874 -0.4064)
			(stroke
				(width 0.1524)
				(type default)
			)
			(layer "B.SilkS")
		)
		(fp_line
			(start 0.7874 -0.4064)
			(end -0.7874 -0.4064)
			(stroke
				(width 0.1524)
				(type default)
			)
			(layer "B.SilkS")
		)
		(fp_line
			(start -0.7874 0.4064)
			(end 0.7874 0.4064)
			(stroke
				(width 0.1524)
				(type default)
			)
			(layer "B.SilkS")
		)
		(fp_line
			(start -0.7874 -0.4064)
			(end -0.7874 0.4064)
			(stroke
				(width 0.1524)
				(type default)
			)
			(layer "B.SilkS")
		)
		(fp_line
			(start 0.67945 0.3048)
			(end 0.67945 -0.305054)
			(stroke
				(width 0.1)
				(type default)
			)
			(layer "B.Fab")
		)
		(fp_line
			(start 0.67945 -0.305054)
			(end 0.12065 -0.305054)
			(stroke
				(width 0.1)
				(type default)
			)
			(layer "B.Fab")
		)
		(fp_line
			(start 0.12065 0.3048)
			(end 0.67945 0.3048)
			(stroke
				(width 0.1)
				(type default)
			)
			(layer "B.Fab")
		)
		(fp_line
			(start 0.12065 0.2794)
			(end 0.12065 0.3048)
			(stroke
				(width 0.1)
				(type default)
			)
			(layer "B.Fab")
		)
		(fp_line
			(start 0.12065 -0.2794)
			(end -0.12065 -0.2794)
			(stroke
				(width 0.1)
				(type default)
			)
			(layer "B.Fab")
		)
		(fp_line
			(start 0.12065 -0.305054)
			(end 0.12065 -0.2794)
			(stroke
				(width 0.1)
				(type default)
			)
			(layer "B.Fab")
		)
		(fp_line
			(start -0.120396 0.3048)
			(end -0.120396 0.2794)
			(stroke
				(width 0.1)
				(type default)
			)
			(layer "B.Fab")
		)
		(fp_line
			(start -0.120396 0.2794)
			(end 0.12065 0.2794)
			(stroke
				(width 0.1)
				(type default)
			)
			(layer "B.Fab")
		)
		(fp_line
			(start -0.12065 -0.2794)
			(end -0.12065 -0.3048)
			(stroke
				(width 0.1)
				(type default)
			)
			(layer "B.Fab")
		)
		(fp_line
			(start -0.12065 -0.3048)
			(end -0.67945 -0.3048)
			(stroke
				(width 0.1)
				(type default)
			)
			(layer "B.Fab")
		)
		(fp_line
			(start -0.67945 0.3048)
			(end -0.120396 0.3048)
			(stroke
				(width 0.1)
				(type default)
			)
			(layer "B.Fab")
		)
		(fp_line
			(start -0.67945 -0.3048)
			(end -0.67945 0.3048)
			(stroke
				(width 0.1)
				(type default)
			)
			(layer "B.Fab")
		)
		(pad "1" smd circle
			(at 0.40005 0)
			(size 0 0)
			(layers "B.Cu" "B.Mask" "B.Paste")
			(net "PWRGD_P12V_FAN_LED_R")
		)
		(pad "2" smd circle
			(at -0.40005 0)
			(size 0 0)
			(layers "B.Cu" "B.Mask" "B.Paste")
			(net "PWRGD_P12V_FAN_LED")
		)
	)
	(footprint ""
		(layer "B.Cu")
		(at 169.210736 -75.311 180)
		(property "Reference" "R5883"
			(at 0 0 0)
			(layer "B.SilkS")
			(hide yes)
			(effects
				(font
					(size 1.27 1.27)
				)
				(justify mirror)
			)
		)
		(property "Value" ""
			(at 0 0 0)
			(layer "B.Fab")
			(effects
				(font
					(size 1.27 1.27)
				)
				(justify mirror)
			)
		)
		(duplicate_pad_numbers_are_jumpers no)
		(fp_line
			(start 0.7874 0.4064)
			(end 0.7874 -0.4064)
			(stroke
				(width 0.1524)
				(type default)
			)
			(layer "B.SilkS")
		)
		(fp_line
			(start 0.7874 -0.4064)
			(end -0.7874 -0.4064)
			(stroke
				(width 0.1524)
				(type default)
			)
			(layer "B.SilkS")
		)
		(fp_line
			(start -0.7874 0.4064)
			(end 0.7874 0.4064)
			(stroke
				(width 0.1524)
				(type default)
			)
			(layer "B.SilkS")
		)
		(fp_line
			(start -0.7874 -0.4064)
			(end -0.7874 0.4064)
			(stroke
				(width 0.1524)
				(type default)
			)
			(layer "B.SilkS")
		)
		(fp_line
			(start 0.67945 0.3048)
			(end 0.67945 -0.305054)
			(stroke
				(width 0.1)
				(type default)
			)
			(layer "B.Fab")
		)
		(fp_line
			(start 0.67945 -0.305054)
			(end 0.12065 -0.305054)
			(stroke
				(width 0.1)
				(type default)
			)
			(layer "B.Fab")
		)
		(fp_line
			(start 0.12065 0.3048)
			(end 0.67945 0.3048)
			(stroke
				(width 0.1)
				(type default)
			)
			(layer "B.Fab")
		)
		(fp_line
			(start 0.12065 0.2794)
			(end 0.12065 0.3048)
			(stroke
				(width 0.1)
				(type default)
			)
			(layer "B.Fab")
		)
		(fp_line
			(start 0.12065 -0.2794)
			(end -0.12065 -0.2794)
			(stroke
				(width 0.1)
				(type default)
			)
			(layer "B.Fab")
		)
		(fp_line
			(start 0.12065 -0.305054)
			(end 0.12065 -0.2794)
			(stroke
				(width 0.1)
				(type default)
			)
			(layer "B.Fab")
		)
		(fp_line
			(start -0.120396 0.3048)
			(end -0.120396 0.2794)
			(stroke
				(width 0.1)
				(type default)
			)
			(layer "B.Fab")
		)
		(fp_line
			(start -0.120396 0.2794)
			(end 0.12065 0.2794)
			(stroke
				(width 0.1)
				(type default)
			)
			(layer "B.Fab")
		)
		(fp_line
			(start -0.12065 -0.2794)
			(end -0.12065 -0.3048)
			(stroke
				(width 0.1)
				(type default)
			)
			(layer "B.Fab")
		)
		(fp_line
			(start -0.12065 -0.3048)
			(end -0.67945 -0.3048)
			(stroke
				(width 0.1)
				(type default)
			)
			(layer "B.Fab")
		)
		(fp_line
			(start -0.67945 0.3048)
			(end -0.120396 0.3048)
			(stroke
				(width 0.1)
				(type default)
			)
			(layer "B.Fab")
		)
		(fp_line
			(start -0.67945 -0.3048)
			(end -0.67945 0.3048)
			(stroke
				(width 0.1)
				(type default)
			)
			(layer "B.Fab")
		)
		(pad "1" smd circle
			(at 0.40005 0)
			(size 0 0)
			(layers "B.Cu" "B.Mask" "B.Paste")
			(net "SMB_P52V_PDB_SDA")
		)
		(pad "2" smd circle
			(at -0.40005 0)
			(size 0 0)
			(layers "B.Cu" "B.Mask" "B.Paste")
			(net "SMB_CM_HS2_3V3SB_DATO")
		)
	)
	(footprint ""
		(layer "B.Cu")
		(at 287.8074 -81.534 180)
		(property "Reference" "PC487"
			(at 0 0 0)
			(layer "B.SilkS")
			(hide yes)
			(effects
				(font
					(size 1.27 1.27)
				)
				(justify mirror)
			)
		)
		(property "Value" ""
			(at 0 0 0)
			(layer "B.Fab")
			(effects
				(font
					(size 1.27 1.27)
				)
				(justify mirror)
			)
		)
		(duplicate_pad_numbers_are_jumpers no)
		(fp_line
			(start 2.2098 0.9398)
			(end 2.2098 -0.9398)
			(stroke
				(width 0.1524)
				(type default)
			)
			(layer "B.SilkS")
		)
		(fp_line
			(start 2.2098 -0.9398)
			(end -2.2098 -0.9398)
			(stroke
				(width 0.1524)
				(type default)
			)
			(layer "B.SilkS")
		)
		(fp_line
			(start -2.2098 0.9398)
			(end 2.2098 0.9398)
			(stroke
				(width 0.1524)
				(type default)
			)
			(layer "B.SilkS")
		)
		(fp_line
			(start -2.2098 -0.9398)
			(end -2.2098 0.9398)
			(stroke
				(width 0.1524)
				(type default)
			)
			(layer "B.SilkS")
		)
		(fp_line
			(start 1.700022 0.899922)
			(end 1.700022 -0.899922)
			(stroke
				(width 0.1)
				(type default)
			)
			(layer "B.Fab")
		)
		(fp_line
			(start 1.700022 -0.899922)
			(end -1.700022 -0.899922)
			(stroke
				(width 0.1)
				(type default)
			)
			(layer "B.Fab")
		)
		(fp_line
			(start -1.700022 0.899922)
			(end 1.700022 0.899922)
			(stroke
				(width 0.1)
				(type default)
			)
			(layer "B.Fab")
		)
		(fp_line
			(start -1.700022 -0.899922)
			(end -1.700022 0.899922)
			(stroke
				(width 0.1)
				(type default)
			)
			(layer "B.Fab")
		)
		(pad "1" smd rect
			(at 1.4732 0 180)
			(size 1.1684 1.5748)
			(layers "B.Cu" "B.Mask" "B.Paste")
			(net "P52V_HS1_DVCC")
		)
		(pad "2" smd rect
			(at -1.4732 0 180)
			(size 1.1684 1.5748)
			(layers "B.Cu" "B.Mask" "B.Paste")
			(net "GND")
		)
	)
	(footprint ""
		(layer "B.Cu")
		(at 278.7904 -74.549 180)
		(property "Reference" "PC590"
			(at 0 0 0)
			(layer "B.SilkS")
			(hide yes)
			(effects
				(font
					(size 1.27 1.27)
				)
				(justify mirror)
			)
		)
		(property "Value" ""
			(at 0 0 0)
			(layer "B.Fab")
			(effects
				(font
					(size 1.27 1.27)
				)
				(justify mirror)
			)
		)
		(duplicate_pad_numbers_are_jumpers no)
		(fp_line
			(start 0.7874 0.4064)
			(end 0.7874 -0.4064)
			(stroke
				(width 0.1524)
				(type default)
			)
			(layer "B.SilkS")
		)
		(fp_line
			(start 0.7874 -0.4064)
			(end -0.7874 -0.4064)
			(stroke
				(width 0.1524)
				(type default)
			)
			(layer "B.SilkS")
		)
		(fp_line
			(start -0.7874 0.4064)
			(end 0.7874 0.4064)
			(stroke
				(width 0.1524)
				(type default)
			)
			(layer "B.SilkS")
		)
		(fp_line
			(start -0.7874 -0.4064)
			(end -0.7874 0.4064)
			(stroke
				(width 0.1524)
				(type default)
			)
			(layer "B.SilkS")
		)
		(fp_line
			(start 0.67945 0.3048)
			(end 0.67945 -0.305054)
			(stroke
				(width 0.1)
				(type default)
			)
			(layer "B.Fab")
		)
		(fp_line
			(start 0.67945 -0.305054)
			(end 0.12065 -0.305054)
			(stroke
				(width 0.1)
				(type default)
			)
			(layer "B.Fab")
		)
		(fp_line
			(start 0.12065 0.3048)
			(end 0.67945 0.3048)
			(stroke
				(width 0.1)
				(type default)
			)
			(layer "B.Fab")
		)
		(fp_line
			(start 0.12065 0.2794)
			(end 0.12065 0.3048)
			(stroke
				(width 0.1)
				(type default)
			)
			(layer "B.Fab")
		)
		(fp_line
			(start 0.12065 -0.2794)
			(end -0.12065 -0.2794)
			(stroke
				(width 0.1)
				(type default)
			)
			(layer "B.Fab")
		)
		(fp_line
			(start 0.12065 -0.305054)
			(end 0.12065 -0.2794)
			(stroke
				(width 0.1)
				(type default)
			)
			(layer "B.Fab")
		)
		(fp_line
			(start -0.120396 0.3048)
			(end -0.120396 0.2794)
			(stroke
				(width 0.1)
				(type default)
			)
			(layer "B.Fab")
		)
		(fp_line
			(start -0.120396 0.2794)
			(end 0.12065 0.2794)
			(stroke
				(width 0.1)
				(type default)
			)
			(layer "B.Fab")
		)
		(fp_line
			(start -0.12065 -0.2794)
			(end -0.12065 -0.3048)
			(stroke
				(width 0.1)
				(type default)
			)
			(layer "B.Fab")
		)
		(fp_line
			(start -0.12065 -0.3048)
			(end -0.67945 -0.3048)
			(stroke
				(width 0.1)
				(type default)
			)
			(layer "B.Fab")
		)
		(fp_line
			(start -0.67945 0.3048)
			(end -0.120396 0.3048)
			(stroke
				(width 0.1)
				(type default)
			)
			(layer "B.Fab")
		)
		(fp_line
			(start -0.67945 -0.3048)
			(end -0.67945 0.3048)
			(stroke
				(width 0.1)
				(type default)
			)
			(layer "B.Fab")
		)
		(pad "1" smd circle
			(at 0.40005 0)
			(size 0 0)
			(layers "B.Cu" "B.Mask" "B.Paste")
			(net "P52V_HS1_ISET")
		)
		(pad "2" smd circle
			(at -0.40005 0)
			(size 0 0)
			(layers "B.Cu" "B.Mask" "B.Paste")
			(net "GND_FIELD_SIGNAL")
		)
	)
	(footprint ""
		(layer "B.Cu")
		(at 336.3214 -50.6476 90)
		(property "Reference" "R5860"
			(at 0 0 90)
			(layer "B.SilkS")
			(hide yes)
			(effects
				(font
					(size 1.27 1.27)
				)
				(justify mirror)
			)
		)
		(property "Value" ""
			(at 0 0 90)
			(layer "B.Fab")
			(effects
				(font
					(size 1.27 1.27)
				)
				(justify mirror)
			)
		)
		(duplicate_pad_numbers_are_jumpers no)
		(fp_line
			(start 0.7874 -0.4064)
			(end -0.7874 -0.4064)
			(stroke
				(width 0.1524)
				(type default)
			)
			(layer "B.SilkS")
		)
		(fp_line
			(start -0.7874 -0.4064)
			(end -0.7874 0.4064)
			(stroke
				(width 0.1524)
				(type default)
			)
			(layer "B.SilkS")
		)
		(fp_line
			(start 0.7874 0.4064)
			(end 0.7874 -0.4064)
			(stroke
				(width 0.1524)
				(type default)
			)
			(layer "B.SilkS")
		)
		(fp_line
			(start -0.7874 0.4064)
			(end 0.7874 0.4064)
			(stroke
				(width 0.1524)
				(type default)
			)
			(layer "B.SilkS")
		)
		(fp_line
			(start 0.67945 -0.305054)
			(end 0.12065 -0.305054)
			(stroke
				(width 0.1)
				(type default)
			)
			(layer "B.Fab")
		)
		(fp_line
			(start 0.12065 -0.305054)
			(end 0.12065 -0.2794)
			(stroke
				(width 0.1)
				(type default)
			)
			(layer "B.Fab")
		)
		(fp_line
			(start -0.12065 -0.3048)
			(end -0.67945 -0.3048)
			(stroke
				(width 0.1)
				(type default)
			)
			(layer "B.Fab")
		)
		(fp_line
			(start -0.67945 -0.3048)
			(end -0.67945 0.3048)
			(stroke
				(width 0.1)
				(type default)
			)
			(layer "B.Fab")
		)
		(fp_line
			(start 0.12065 -0.2794)
			(end -0.12065 -0.2794)
			(stroke
				(width 0.1)
				(type default)
			)
			(layer "B.Fab")
		)
		(fp_line
			(start -0.12065 -0.2794)
			(end -0.12065 -0.3048)
			(stroke
				(width 0.1)
				(type default)
			)
			(layer "B.Fab")
		)
		(fp_line
			(start 0.12065 0.2794)
			(end 0.12065 0.3048)
			(stroke
				(width 0.1)
				(type default)
			)
			(layer "B.Fab")
		)
		(fp_line
			(start -0.120396 0.2794)
			(end 0.12065 0.2794)
			(stroke
				(width 0.1)
				(type default)
			)
			(layer "B.Fab")
		)
		(fp_line
			(start 0.67945 0.3048)
			(end 0.67945 -0.305054)
			(stroke
				(width 0.1)
				(type default)
			)
			(layer "B.Fab")
		)
		(fp_line
			(start 0.12065 0.3048)
			(end 0.67945 0.3048)
			(stroke
				(width 0.1)
				(type default)
			)
			(layer "B.Fab")
		)
		(fp_line
			(start -0.120396 0.3048)
			(end -0.120396 0.2794)
			(stroke
				(width 0.1)
				(type default)
			)
			(layer "B.Fab")
		)
		(fp_line
			(start -0.67945 0.3048)
			(end -0.120396 0.3048)
			(stroke
				(width 0.1)
				(type default)
			)
			(layer "B.Fab")
		)
		(pad "1" smd circle
			(at 0.40005 0 270)
			(size 0 0)
			(layers "B.Cu" "B.Mask" "B.Paste")
			(net "P52V_HS1_GATE1_R")
		)
		(pad "2" smd circle
			(at -0.40005 0 270)
			(size 0 0)
			(layers "B.Cu" "B.Mask" "B.Paste")
			(net "P52V_HS1_1272_GATE")
		)
	)
	(footprint ""
		(layer "B.Cu")
		(at 275.8694 -76.454 -90)
		(property "Reference" "PC575"
			(at 0 0 90)
			(layer "B.SilkS")
			(hide yes)
			(effects
				(font
					(size 1.27 1.27)
				)
				(justify mirror)
			)
		)
		(property "Value" ""
			(at 0 0 90)
			(layer "B.Fab")
			(effects
				(font
					(size 1.27 1.27)
				)
				(justify mirror)
			)
		)
		(duplicate_pad_numbers_are_jumpers no)
		(fp_line
			(start -0.7874 0.4064)
			(end 0.7874 0.4064)
			(stroke
				(width 0.1524)
				(type default)
			)
			(layer "B.SilkS")
		)
		(fp_line
			(start 0.7874 0.4064)
			(end 0.7874 -0.4064)
			(stroke
				(width 0.1524)
				(type default)
			)
			(layer "B.SilkS")
		)
		(fp_line
			(start -0.7874 -0.4064)
			(end -0.7874 0.4064)
			(stroke
				(width 0.1524)
				(type default)
			)
			(layer "B.SilkS")
		)
		(fp_line
			(start 0.7874 -0.4064)
			(end -0.7874 -0.4064)
			(stroke
				(width 0.1524)
				(type default)
			)
			(layer "B.SilkS")
		)
		(fp_line
			(start -0.67945 0.3048)
			(end -0.120396 0.3048)
			(stroke
				(width 0.1)
				(type default)
			)
			(layer "B.Fab")
		)
		(fp_line
			(start -0.120396 0.3048)
			(end -0.120396 0.2794)
			(stroke
				(width 0.1)
				(type default)
			)
			(layer "B.Fab")
		)
		(fp_line
			(start 0.12065 0.3048)
			(end 0.67945 0.3048)
			(stroke
				(width 0.1)
				(type default)
			)
			(layer "B.Fab")
		)
		(fp_line
			(start 0.67945 0.3048)
			(end 0.67945 -0.305054)
			(stroke
				(width 0.1)
				(type default)
			)
			(layer "B.Fab")
		)
		(fp_line
			(start -0.120396 0.2794)
			(end 0.12065 0.2794)
			(stroke
				(width 0.1)
				(type default)
			)
			(layer "B.Fab")
		)
		(fp_line
			(start 0.12065 0.2794)
			(end 0.12065 0.3048)
			(stroke
				(width 0.1)
				(type default)
			)
			(layer "B.Fab")
		)
		(fp_line
			(start -0.12065 -0.2794)
			(end -0.12065 -0.3048)
			(stroke
				(width 0.1)
				(type default)
			)
			(layer "B.Fab")
		)
		(fp_line
			(start 0.12065 -0.2794)
			(end -0.12065 -0.2794)
			(stroke
				(width 0.1)
				(type default)
			)
			(layer "B.Fab")
		)
		(fp_line
			(start -0.67945 -0.3048)
			(end -0.67945 0.3048)
			(stroke
				(width 0.1)
				(type default)
			)
			(layer "B.Fab")
		)
		(fp_line
			(start -0.12065 -0.3048)
			(end -0.67945 -0.3048)
			(stroke
				(width 0.1)
				(type default)
			)
			(layer "B.Fab")
		)
		(fp_line
			(start 0.12065 -0.305054)
			(end 0.12065 -0.2794)
			(stroke
				(width 0.1)
				(type default)
			)
			(layer "B.Fab")
		)
		(fp_line
			(start 0.67945 -0.305054)
			(end 0.12065 -0.305054)
			(stroke
				(width 0.1)
				(type default)
			)
			(layer "B.Fab")
		)
		(pad "1" smd circle
			(at 0.40005 0 90)
			(size 0 0)
			(layers "B.Cu" "B.Mask" "B.Paste")
			(net "P52V_HS1_OV")
		)
		(pad "2" smd circle
			(at -0.40005 0 90)
			(size 0 0)
			(layers "B.Cu" "B.Mask" "B.Paste")
			(net "GND_FIELD_SIGNAL")
		)
	)
	(footprint ""
		(layer "B.Cu")
		(at 260.2484 -49.149 -90)
		(property "Reference" "R398"
			(at 0 0 90)
			(layer "B.SilkS")
			(hide yes)
			(effects
				(font
					(size 1.27 1.27)
				)
				(justify mirror)
			)
		)
		(property "Value" ""
			(at 0 0 90)
			(layer "B.Fab")
			(effects
				(font
					(size 1.27 1.27)
				)
				(justify mirror)
			)
		)
		(duplicate_pad_numbers_are_jumpers no)
		(fp_line
			(start -1.651 0.8382)
			(end 1.651 0.8382)
			(stroke
				(width 0.1524)
				(type default)
			)
			(layer "B.SilkS")
		)
		(fp_line
			(start 1.651 0.8382)
			(end 1.651 -0.8382)
			(stroke
				(width 0.1524)
				(type default)
			)
			(layer "B.SilkS")
		)
		(fp_line
			(start -1.651 -0.8382)
			(end -1.651 0.8382)
			(stroke
				(width 0.1524)
				(type default)
			)
			(layer "B.SilkS")
		)
		(fp_line
			(start 1.651 -0.8382)
			(end -1.651 -0.8382)
			(stroke
				(width 0.1524)
				(type default)
			)
			(layer "B.SilkS")
		)
		(fp_line
			(start -1.560576 0.7366)
			(end -1.560576 -0.7366)
			(stroke
				(width 0.1)
				(type default)
			)
			(layer "B.Fab")
		)
		(fp_line
			(start -1.524 0.7366)
			(end -1.560576 0.7366)
			(stroke
				(width 0.1)
				(type default)
			)
			(layer "B.Fab")
		)
		(fp_line
			(start 1.524 0.7366)
			(end -1.524 0.7366)
			(stroke
				(width 0.1)
				(type default)
			)
			(layer "B.Fab")
		)
		(fp_line
			(start 1.559814 0.7366)
			(end 1.524 0.7366)
			(stroke
				(width 0.1)
				(type default)
			)
			(layer "B.Fab")
		)
		(fp_line
			(start -1.560576 -0.7366)
			(end -1.524 -0.7366)
			(stroke
				(width 0.1)
				(type default)
			)
			(layer "B.Fab")
		)
		(fp_line
			(start -1.524 -0.7366)
			(end 1.524 -0.7366)
			(stroke
				(width 0.1)
				(type default)
			)
			(layer "B.Fab")
		)
		(fp_line
			(start 1.524 -0.7366)
			(end 1.559814 -0.7366)
			(stroke
				(width 0.1)
				(type default)
			)
			(layer "B.Fab")
		)
		(fp_line
			(start 1.559814 -0.7366)
			(end 1.559814 0.7366)
			(stroke
				(width 0.1)
				(type default)
			)
			(layer "B.Fab")
		)
		(pad "1" smd rect
			(at 0.94996 0 270)
			(size 1.1176 1.3716)
			(layers "B.Cu" "B.Mask" "B.Paste")
			(net "P52V_1_FUSE_1")
		)
		(pad "2" smd rect
			(at -0.94996 0 270)
			(size 1.1176 1.3716)
			(layers "B.Cu" "B.Mask" "B.Paste")
			(net "FM_HS1_EN_FUSE")
		)
	)
)
